(kicad_pcb
	(version 20260206)
	(generator "pcbnew")
	(generator_version "10.0")
	(general
		(thickness 1.6)
		(legacy_teardrops no)
	)
	(paper "A4")
	(title_block
		(title "Bryce Canyon_R.DPB_16317-1_OCP.brd")
		(comment 1 "Bryce Canyon / footprints 195-200 of 2099")
	)
	(layers
		(0 "F.Cu" signal "TOP")
		(4 "In1.Cu" signal "L2GND")
		(6 "In2.Cu" signal "L3")
		(8 "In3.Cu" signal "L4VCC")
		(10 "In4.Cu" signal "L5VCC")
		(12 "In5.Cu" signal "L6")
		(14 "In6.Cu" signal "L7GND")
		(2 "B.Cu" signal "BOTTOM")
		(9 "F.Adhes" user "F.Adhesive")
		(11 "B.Adhes" user "B.Adhesive")
		(13 "F.Paste" user "Package Geometry/Pastemask Top")
		(15 "B.Paste" user "Package Geometry/Pastemask Bottom")
		(5 "F.SilkS" user "Ref Des/Silkscreen Top")
		(7 "B.SilkS" user "Ref Des/Silkscreen Bottom")
		(1 "F.Mask" user "Board Geometry/Soldermask Top")
		(3 "B.Mask" user "Board Geometry/Soldermask Bottom")
		(17 "Dwgs.User" user "User.Drawings")
		(19 "Cmts.User" user "User.Comments")
		(21 "Eco1.User" user "User.Eco1")
		(23 "Eco2.User" user "User.Eco2")
		(25 "Edge.Cuts" user "Board Geometry/Outline")
		(27 "Margin" user)
		(31 "F.CrtYd" user "Package Geometry/Place Bound Top")
		(29 "B.CrtYd" user "Package Geometry/Place Bound Bottom")
		(35 "F.Fab" user "Ref Des/Assembly Top")
		(33 "B.Fab" user "Ref Des/Assembly Bottom")
	)
	(footprint ""
		(layer "F.Cu")
		(at 319.83553 -99.820476 90)
		(property "Reference" "Q260"
			(at 0 0 90)
			(layer "F.SilkS")
			(hide yes)
			(effects
				(font
					(size 1.27 1.27)
				)
			)
		)
		(property "Value" "SSM3K324R-GP"
			(at 0.127 -8.9662 90)
			(unlocked yes)
			(layer "F.Fab")
			(hide yes)
			(effects
				(font
					(size 1.016 1.016)
					(thickness 0.1524)
				)
			)
		)
		(property "Device Type" "SOT23DGS2D4H35"
			(at 0.127 -10.4902 90)
			(unlocked yes)
			(layer "F.Fab")
			(hide yes)
			(effects
				(font
					(size 1.016 1.016)
					(thickness 0.1524)
				)
			)
		)
		(duplicate_pad_numbers_are_jumpers no)
		(fp_line
			(start 1.651 -1.778)
			(end -1.651 -1.778)
			(stroke
				(width 0.1524)
				(type default)
			)
			(layer "F.SilkS")
		)
		(fp_line
			(start -1.651 -1.778)
			(end -1.651 1.778)
			(stroke
				(width 0.1524)
				(type default)
			)
			(layer "F.SilkS")
		)
		(fp_line
			(start 1.651 1.778)
			(end 1.651 -1.778)
			(stroke
				(width 0.1524)
				(type default)
			)
			(layer "F.SilkS")
		)
		(fp_line
			(start -1.651 1.778)
			(end 1.651 1.778)
			(stroke
				(width 0.1524)
				(type default)
			)
			(layer "F.SilkS")
		)
		(fp_poly
			(pts
				(xy -1.778 1.8796) (xy -1.778 -1.8796) (xy 1.778 -1.8796) (xy 1.778 1.8796)
			)
			(stroke
				(width 0)
				(type default)
			)
			(fill no)
			(layer "F.CrtYd")
		)
		(fp_poly
			(pts
				(xy -1.778 1.8796) (xy -1.778 -1.8796) (xy 1.778 -1.8796) (xy 1.778 1.8796)
			)
			(stroke
				(width 0)
				(type default)
			)
			(fill no)
			(layer "F.Fab")
		)
		(pad "D" smd custom
			(at 0 -0.9525 90)
			(size 0.1905 0.1905)
			(layers "F.Cu" "F.Mask" "F.Paste")
			(net "DRV_ACT_18_N")
			(options
				(clearance outline)
				(anchor circle)
			)
			(primitives
				(gr_poly
					(pts
						(arc
							(start -0.1778 0.5715)
							(mid -0.321484 0.511984)
							(end -0.381 0.3683)
						)
						(arc
							(start -0.381 -0.3683)
							(mid -0.321484 -0.511984)
							(end -0.1778 -0.5715)
						)
						(arc
							(start 0.1778 -0.5715)
							(mid 0.321484 -0.511984)
							(end 0.381 -0.3683)
						)
						(arc
							(start 0.381 0.3683)
							(mid 0.321484 0.511984)
							(end 0.1778 0.5715)
						)
					)
					(width 0)
					(fill yes)
				)
			)
		)
		(pad "G" smd custom
			(at -0.98425 0.9525 90)
			(size 0.1905 0.1905)
			(layers "F.Cu" "F.Mask" "F.Paste")
			(net "DRIVE_B_18_ACT")
			(options
				(clearance outline)
				(anchor circle)
			)
			(primitives
				(gr_poly
					(pts
						(arc
							(start -0.1778 0.5715)
							(mid -0.321484 0.511984)
							(end -0.381 0.3683)
						)
						(arc
							(start -0.381 -0.3683)
							(mid -0.321484 -0.511984)
							(end -0.1778 -0.5715)
						)
						(arc
							(start 0.1778 -0.5715)
							(mid 0.321484 -0.511984)
							(end 0.381 -0.3683)
						)
						(arc
							(start 0.381 0.3683)
							(mid 0.321484 0.511984)
							(end 0.1778 0.5715)
						)
					)
					(width 0)
					(fill yes)
				)
			)
		)
		(pad "S" smd custom
			(at 0.98425 0.9525 90)
			(size 0.1905 0.1905)
			(layers "F.Cu" "F.Mask" "F.Paste")
			(net "GND")
			(options
				(clearance outline)
				(anchor circle)
			)
			(primitives
				(gr_poly
					(pts
						(arc
							(start -0.1778 0.5715)
							(mid -0.321484 0.511984)
							(end -0.381 0.3683)
						)
						(arc
							(start -0.381 -0.3683)
							(mid -0.321484 -0.511984)
							(end -0.1778 -0.5715)
						)
						(arc
							(start 0.1778 -0.5715)
							(mid 0.321484 -0.511984)
							(end 0.381 -0.3683)
						)
						(arc
							(start 0.381 0.3683)
							(mid 0.321484 0.511984)
							(end 0.1778 0.5715)
						)
					)
					(width 0)
					(fill yes)
				)
			)
		)
	)
	(footprint ""
		(layer "F.Cu")
		(at 98.425 -263.144 -90)
		(property "Reference" "R191"
			(at 0 0 270)
			(layer "F.SilkS")
			(hide yes)
			(effects
				(font
					(size 1.27 1.27)
				)
			)
		)
		(property "Value" "10KR2F-2-GP"
			(at 0.064008 -3.993896 270)
			(unlocked yes)
			(layer "F.Fab")
			(hide yes)
			(effects
				(font
					(size 1.016 1.016)
					(thickness 0.1524)
				)
			)
		)
		(property "Device Type" "R402H16"
			(at 0.064008 -5.517896 270)
			(unlocked yes)
			(layer "F.Fab")
			(hide yes)
			(effects
				(font
					(size 1.016 1.016)
					(thickness 0.1524)
				)
			)
		)
		(duplicate_pad_numbers_are_jumpers no)
		(fp_line
			(start -0.508 -0.9398)
			(end -0.508 0.9398)
			(stroke
				(width 0.1524)
				(type default)
			)
			(layer "F.SilkS")
		)
		(fp_line
			(start 0.508 -0.9398)
			(end -0.508 -0.9398)
			(stroke
				(width 0.1524)
				(type default)
			)
			(layer "F.SilkS")
		)
		(fp_rect
			(start -0.508 0.9398)
			(end 0.508 -0.9398)
			(stroke
				(width 0)
				(type default)
			)
			(fill no)
			(layer "F.CrtYd")
		)
		(fp_rect
			(start -0.508 0.9398)
			(end 0.508 -0.9398)
			(stroke
				(width 0)
				(type default)
			)
			(fill no)
			(layer "F.Fab")
		)
		(pad "1" smd custom
			(at 0 -0.4445 270)
			(size 0.1397 0.1397)
			(layers "F.Cu" "F.Mask" "F.Paste")
			(net "P3V3_STBY_B")
			(options
				(clearance outline)
				(anchor circle)
			)
			(primitives
				(gr_poly
					(pts
						(arc
							(start -0.1778 -0.2794)
							(mid -0.249642 -0.249642)
							(end -0.2794 -0.1778)
						)
						(arc
							(start -0.2794 0.1778)
							(mid -0.249642 0.249642)
							(end -0.1778 0.2794)
						)
						(arc
							(start 0.1778 0.2794)
							(mid 0.249642 0.249642)
							(end 0.2794 0.1778)
						)
						(arc
							(start 0.2794 -0.1778)
							(mid 0.249642 -0.249642)
							(end 0.1778 -0.2794)
						)
					)
					(width 0)
					(fill yes)
				)
			)
		)
		(pad "2" smd custom
			(at 0 0.4445 270)
			(size 0.1397 0.1397)
			(layers "F.Cu" "F.Mask" "F.Paste")
			(net "HDD_PRSNT_2")
			(options
				(clearance outline)
				(anchor circle)
			)
			(primitives
				(gr_poly
					(pts
						(arc
							(start -0.1778 -0.2794)
							(mid -0.249642 -0.249642)
							(end -0.2794 -0.1778)
						)
						(arc
							(start -0.2794 0.1778)
							(mid -0.249642 0.249642)
							(end -0.1778 0.2794)
						)
						(arc
							(start 0.1778 0.2794)
							(mid 0.249642 0.249642)
							(end 0.2794 0.1778)
						)
						(arc
							(start 0.2794 -0.1778)
							(mid 0.249642 -0.249642)
							(end 0.1778 -0.2794)
						)
					)
					(width 0)
					(fill yes)
				)
			)
		)
	)
	(footprint ""
		(layer "F.Cu")
		(at 458.216 -131.318 -90)
		(property "Reference" "Q107"
			(at 0 0 270)
			(layer "F.SilkS")
			(hide yes)
			(effects
				(font
					(size 1.27 1.27)
				)
			)
		)
		(property "Value" "2N7002KDW-GP"
			(at -2.3622 -8.2042 270)
			(unlocked yes)
			(layer "F.Fab")
			(hide yes)
			(effects
				(font
					(size 1.016 1.016)
					(thickness 0.1524)
				)
			)
		)
		(property "Device Type" "SOT-363H44"
			(at -2.3622 -10.1092 270)
			(unlocked yes)
			(layer "F.Fab")
			(hide yes)
			(effects
				(font
					(size 1.016 1.016)
					(thickness 0.1524)
				)
			)
		)
		(duplicate_pad_numbers_are_jumpers no)
		(fp_line
			(start -1.4478 1.7018)
			(end 1.4478 1.7018)
			(stroke
				(width 0.1524)
				(type default)
			)
			(layer "F.SilkS")
		)
		(fp_line
			(start 1.4478 1.7018)
			(end 1.4478 -1.7018)
			(stroke
				(width 0.1524)
				(type default)
			)
			(layer "F.SilkS")
		)
		(fp_line
			(start -1.27 1.524)
			(end -1.27 0.6604)
			(stroke
				(width 0.4826)
				(type default)
			)
			(layer "F.SilkS")
		)
		(fp_line
			(start -1.4478 -1.7018)
			(end -1.4478 1.7018)
			(stroke
				(width 0.1524)
				(type default)
			)
			(layer "F.SilkS")
		)
		(fp_line
			(start 1.4478 -1.7018)
			(end -1.4478 -1.7018)
			(stroke
				(width 0.1524)
				(type default)
			)
			(layer "F.SilkS")
		)
		(fp_poly
			(pts
				(xy -1.524 -1.778) (xy 1.524 -1.778) (xy 1.524 1.778) (xy -1.524 1.778)
			)
			(stroke
				(width 0)
				(type default)
			)
			(fill no)
			(layer "F.CrtYd")
		)
		(fp_poly
			(pts
				(xy -1.524 -1.778) (xy 1.524 -1.778) (xy 1.524 1.778) (xy -1.524 1.778)
			)
			(stroke
				(width 0)
				(type default)
			)
			(fill no)
			(layer "F.Fab")
		)
		(pad "1" smd rect
			(at -0.65024 0.9398 270)
			(size 0.4064 1.016)
			(layers "F.Cu" "F.Mask" "F.Paste")
			(net "GND")
		)
		(pad "2" smd rect
			(at 0 0.9398 270)
			(size 0.4064 1.016)
			(layers "F.Cu" "F.Mask" "F.Paste")
			(net "SW_PWR_R_HDD22")
		)
		(pad "3" smd rect
			(at 0.65024 0.9398 270)
			(size 0.4064 1.016)
			(layers "F.Cu" "F.Mask" "F.Paste")
			(net "SW_HDD_P22")
		)
		(pad "4" smd rect
			(at 0.65024 -0.9398 270)
			(size 0.4064 1.016)
			(layers "F.Cu" "F.Mask" "F.Paste")
			(net "GND")
		)
		(pad "5" smd rect
			(at 0 -0.9398 270)
			(size 0.4064 1.016)
			(layers "F.Cu" "F.Mask" "F.Paste")
			(net "SW_HDD_G22")
		)
		(pad "6" smd rect
			(at -0.65024 -0.9398 270)
			(size 0.4064 1.016)
			(layers "F.Cu" "F.Mask" "F.Paste")
			(net "SW_HDD_R22")
		)
	)
	(footprint ""
		(layer "F.Cu")
		(at 361.315 -45.339 180)
		(property "Reference" "C439"
			(at 0 0 180)
			(layer "F.SilkS")
			(hide yes)
			(effects
				(font
					(size 1.27 1.27)
				)
			)
		)
		(property "Value" "SC1U25V3KX-GP"
			(at 0 -2.8194 180)
			(unlocked yes)
			(layer "F.Fab")
			(hide yes)
			(effects
				(font
					(size 1.016 1.016)
					(thickness 0.1524)
				)
			)
		)
		(property "Device Type" "C603H36"
			(at 0 -4.3434 180)
			(unlocked yes)
			(layer "F.Fab")
			(hide yes)
			(effects
				(font
					(size 1.016 1.016)
					(thickness 0.1524)
				)
			)
		)
		(duplicate_pad_numbers_are_jumpers no)
		(fp_line
			(start 0.508 0)
			(end -0.508 0)
			(stroke
				(width 0.2032)
				(type default)
			)
			(layer "F.SilkS")
		)
		(fp_rect
			(start -0.5842 1.3335)
			(end 0.5842 -1.3335)
			(stroke
				(width 0)
				(type default)
			)
			(fill no)
			(layer "F.CrtYd")
		)
		(fp_rect
			(start -0.5842 1.3335)
			(end 0.5842 -1.3335)
			(stroke
				(width 0)
				(type default)
			)
			(fill no)
			(layer "F.Fab")
		)
		(pad "1" smd custom
			(at 0 -0.762 180)
			(size 0.2159 0.2159)
			(layers "F.Cu" "F.Mask" "F.Paste")
			(net "P12V_HDD31")
			(options
				(clearance outline)
				(anchor circle)
			)
			(primitives
				(gr_poly
					(pts
						(arc
							(start -0.3302 -0.4318)
							(mid -0.402042 -0.402042)
							(end -0.4318 -0.3302)
						)
						(arc
							(start -0.4318 0.3302)
							(mid -0.402042 0.402042)
							(end -0.3302 0.4318)
						)
						(arc
							(start 0.3302 0.4318)
							(mid 0.402042 0.402042)
							(end 0.4318 0.3302)
						)
						(arc
							(start 0.4318 -0.3302)
							(mid 0.402042 -0.402042)
							(end 0.3302 -0.4318)
						)
					)
					(width 0)
					(fill yes)
				)
			)
		)
		(pad "2" smd custom
			(at 0 0.762 180)
			(size 0.2159 0.2159)
			(layers "F.Cu" "F.Mask" "F.Paste")
			(net "GND")
			(options
				(clearance outline)
				(anchor circle)
			)
			(primitives
				(gr_poly
					(pts
						(arc
							(start -0.3302 -0.4318)
							(mid -0.402042 -0.402042)
							(end -0.4318 -0.3302)
						)
						(arc
							(start -0.4318 0.3302)
							(mid -0.402042 0.402042)
							(end -0.3302 0.4318)
						)
						(arc
							(start 0.3302 0.4318)
							(mid 0.402042 0.402042)
							(end 0.4318 0.3302)
						)
						(arc
							(start 0.4318 -0.3302)
							(mid 0.402042 -0.402042)
							(end 0.3302 -0.4318)
						)
					)
					(width 0)
					(fill yes)
				)
			)
		)
	)
	(footprint ""
		(layer "F.Cu")
		(at 260.970522 -366.115346)
		(property "Reference" "U1"
			(at 0 0 0)
			(layer "F.SilkS")
			(hide yes)
			(effects
				(font
					(size 1.27 1.27)
				)
			)
		)
		(property "Value" "SN74LVC1G08DCKR-GP"
			(at -2.3368 -8.6868 0)
			(unlocked yes)
			(layer "F.Fab")
			(hide yes)
			(effects
				(font
					(size 1.016 1.016)
					(thickness 0.1524)
				)
			)
		)
		(property "Device Type" "SC70-5H44"
			(at -2.3114 -10.414 0)
			(unlocked yes)
			(layer "F.Fab")
			(hide yes)
			(effects
				(font
					(size 1.016 1.016)
					(thickness 0.1524)
				)
			)
		)
		(duplicate_pad_numbers_are_jumpers no)
		(fp_line
			(start -1.27 -1.7018)
			(end 1.27 -1.7018)
			(stroke
				(width 0.1524)
				(type default)
			)
			(layer "F.SilkS")
		)
		(fp_line
			(start -1.27 1.7018)
			(end -1.27 -1.7018)
			(stroke
				(width 0.1524)
				(type default)
			)
			(layer "F.SilkS")
		)
		(fp_line
			(start 0.6604 -1.8034)
			(end 1.3843 -1.8034)
			(stroke
				(width 0.3302)
				(type default)
			)
			(layer "F.SilkS")
		)
		(fp_line
			(start 1.27 -1.7018)
			(end 1.27 1.7018)
			(stroke
				(width 0.1524)
				(type default)
			)
			(layer "F.SilkS")
		)
		(fp_line
			(start 1.27 1.7018)
			(end -1.27 1.7018)
			(stroke
				(width 0.1524)
				(type default)
			)
			(layer "F.SilkS")
		)
		(fp_line
			(start 1.3843 -1.8034)
			(end 1.3843 -1.1176)
			(stroke
				(width 0.3302)
				(type default)
			)
			(layer "F.SilkS")
		)
		(fp_rect
			(start -1.524 1.9558)
			(end 1.524 -1.9558)
			(stroke
				(width 0)
				(type default)
			)
			(fill no)
			(layer "F.CrtYd")
		)
		(fp_poly
			(pts
				(xy -1.524 -1.9558) (xy 1.524 -1.9558) (xy 1.524 1.9558) (xy -1.524 1.9558)
			)
			(stroke
				(width 0)
				(type default)
			)
			(fill no)
			(layer "F.Fab")
		)
		(pad "1" smd rect
			(at 0.65024 -0.8255)
			(size 0.4064 1.2192)
			(layers "F.Cu" "F.Mask" "F.Paste")
			(net "P12V_IN_PGOOD")
		)
		(pad "2" smd rect
			(at 0 -0.8255)
			(size 0.4064 1.2192)
			(layers "F.Cu" "F.Mask" "F.Paste")
			(net "DPB_PWR_BTN_BUF_B")
		)
		(pad "3" smd rect
			(at -0.65024 -0.8255)
			(size 0.4064 1.2192)
			(layers "F.Cu" "F.Mask" "F.Paste")
			(net "GND")
		)
		(pad "4" smd rect
			(at -0.65024 0.8255)
			(size 0.4064 1.2192)
			(layers "F.Cu" "F.Mask" "F.Paste")
			(net "MB3_HS_ENABLE")
		)
		(pad "5" smd rect
			(at 0.65024 0.8255)
			(size 0.4064 1.2192)
			(layers "F.Cu" "F.Mask" "F.Paste")
			(net "P3V3_IN_BIAS")
		)
	)
	(footprint ""
		(layer "F.Cu")
		(at 375.004076 -214.757 180)
		(property "Reference" "Q227"
			(at 0 0 180)
			(layer "F.SilkS")
			(hide yes)
			(effects
				(font
					(size 1.27 1.27)
				)
			)
		)
		(property "Value" "2N7002K-2-GP"
			(at 0.127 -8.9662 180)
			(unlocked yes)
			(layer "F.Fab")
			(hide yes)
			(effects
				(font
					(size 1.016 1.016)
					(thickness 0.1524)
				)
			)
		)
		(property "Device Type" "SOT23DGS2D4H44"
			(at 0.127 -10.4902 180)
			(unlocked yes)
			(layer "F.Fab")
			(hide yes)
			(effects
				(font
					(size 1.016 1.016)
					(thickness 0.1524)
				)
			)
		)
		(duplicate_pad_numbers_are_jumpers no)
		(fp_line
			(start 1.651 1.778)
			(end 1.651 -1.778)
			(stroke
				(width 0.1524)
				(type default)
			)
			(layer "F.SilkS")
		)
		(fp_line
			(start 1.651 -1.778)
			(end -1.651 -1.778)
			(stroke
				(width 0.1524)
				(type default)
			)
			(layer "F.SilkS")
		)
		(fp_line
			(start -1.651 1.778)
			(end 1.651 1.778)
			(stroke
				(width 0.1524)
				(type default)
			)
			(layer "F.SilkS")
		)
		(fp_line
			(start -1.651 -1.778)
			(end -1.651 1.778)
			(stroke
				(width 0.1524)
				(type default)
			)
			(layer "F.SilkS")
		)
		(fp_poly
			(pts
				(xy -1.778 1.8796) (xy -1.778 -1.8796) (xy 1.778 -1.8796) (xy 1.778 1.8796)
			)
			(stroke
				(width 0)
				(type default)
			)
			(fill no)
			(layer "F.CrtYd")
		)
		(fp_poly
			(pts
				(xy -1.778 1.8796) (xy -1.778 -1.8796) (xy 1.778 -1.8796) (xy 1.778 1.8796)
			)
			(stroke
				(width 0)
				(type default)
			)
			(fill no)
			(layer "F.Fab")
		)
		(pad "D" smd custom
			(at 0 -0.9525 180)
			(size 0.1905 0.1905)
			(layers "F.Cu" "F.Mask" "F.Paste")
			(net "FLT_HDD8_N")
			(options
				(clearance outline)
				(anchor circle)
			)
			(primitives
				(gr_poly
					(pts
						(arc
							(start -0.1778 0.5715)
							(mid -0.321484 0.511984)
							(end -0.381 0.3683)
						)
						(arc
							(start -0.381 -0.3683)
							(mid -0.321484 -0.511984)
							(end -0.1778 -0.5715)
						)
						(arc
							(start 0.1778 -0.5715)
							(mid 0.321484 -0.511984)
							(end 0.381 -0.3683)
						)
						(arc
							(start 0.381 0.3683)
							(mid 0.321484 0.511984)
							(end 0.1778 0.5715)
						)
					)
					(width 0)
					(fill yes)
				)
			)
		)
		(pad "G" smd custom
			(at -0.98425 0.9525 180)
			(size 0.1905 0.1905)
			(layers "F.Cu" "F.Mask" "F.Paste")
			(net "DRIVE_B_8_FLT_LED")
			(options
				(clearance outline)
				(anchor circle)
			)
			(primitives
				(gr_poly
					(pts
						(arc
							(start -0.1778 0.5715)
							(mid -0.321484 0.511984)
							(end -0.381 0.3683)
						)
						(arc
							(start -0.381 -0.3683)
							(mid -0.321484 -0.511984)
							(end -0.1778 -0.5715)
						)
						(arc
							(start 0.1778 -0.5715)
							(mid 0.321484 -0.511984)
							(end 0.381 -0.3683)
						)
						(arc
							(start 0.381 0.3683)
							(mid 0.321484 0.511984)
							(end 0.1778 0.5715)
						)
					)
					(width 0)
					(fill yes)
				)
			)
		)
		(pad "S" smd custom
			(at 0.98425 0.9525 180)
			(size 0.1905 0.1905)
			(layers "F.Cu" "F.Mask" "F.Paste")
			(net "GND")
			(options
				(clearance outline)
				(anchor circle)
			)
			(primitives
				(gr_poly
					(pts
						(arc
							(start -0.1778 0.5715)
							(mid -0.321484 0.511984)
							(end -0.381 0.3683)
						)
						(arc
							(start -0.381 -0.3683)
							(mid -0.321484 -0.511984)
							(end -0.1778 -0.5715)
						)
						(arc
							(start 0.1778 -0.5715)
							(mid 0.321484 -0.511984)
							(end 0.381 -0.3683)
						)
						(arc
							(start 0.381 0.3683)
							(mid 0.321484 0.511984)
							(end 0.1778 0.5715)
						)
					)
					(width 0)
					(fill yes)
				)
			)
		)
	)
)
